(kicad_pcb
	(version 20241229)
	(generator "pcbnew")
	(generator_version "9.0")
	(general
		(thickness 1.294)
		(legacy_teardrops no)
	)
	(paper "A3")
	(title_block
		(title "Kintex 410T devboard")
		(date "2024-04-03")
		(rev "1.1.2")
		(comment 9 "footprints 458-462 of 975")
	)
	(layers
		(0 "F.Cu" mixed)
		(4 "In1.Cu" power)
		(6 "In2.Cu" power)
		(8 "In3.Cu" mixed)
		(10 "In4.Cu" power)
		(12 "In5.Cu" mixed)
		(14 "In6.Cu" power)
		(16 "In7.Cu" mixed)
		(18 "In8.Cu" power)
		(2 "B.Cu" mixed)
		(9 "F.Adhes" user "F.Adhesive")
		(11 "B.Adhes" user "B.Adhesive")
		(13 "F.Paste" user)
		(15 "B.Paste" user)
		(5 "F.SilkS" user "F.Silkscreen")
		(7 "B.SilkS" user "B.Silkscreen")
		(1 "F.Mask" user)
		(3 "B.Mask" user)
		(17 "Dwgs.User" user "User.Drawings")
		(19 "Cmts.User" user "User.Comments")
		(21 "Eco1.User" user "User.Eco1")
		(23 "Eco2.User" user "User.Eco2")
		(25 "Edge.Cuts" user)
		(27 "Margin" user)
		(31 "F.CrtYd" user "F.Courtyard")
		(29 "B.CrtYd" user "B.Courtyard")
		(35 "F.Fab" user)
		(33 "B.Fab" user)
	)
	(footprint "antmicro-footprints:SC70-3"
		(layer "F.Cu")
		(at 258.4 93.4)
		(property "Reference" "Q13"
			(at -1.6 1.1 90)
			(layer "F.SilkS")
			(effects
				(font
					(size 0.7 0.7)
					(thickness 0.15)
				)
				(justify left bottom)
			)
		)
		(property "Value" "BSS138PW"
			(at 0 2.3 0)
			(layer "F.Fab")
			(effects
				(font
					(size 0.7 0.7)
					(thickness 0.15)
				)
				(justify left bottom)
			)
		)
		(property "Description" "Power MOSFET, N Channel, 60 V, 320 mA, 0.9 ohm, SOT-323, Surface Mount"
			(at 0 0 0)
			(layer "F.Fab")
			(hide yes)
			(effects
				(font
					(size 1.27 1.27)
					(thickness 0.15)
				)
			)
		)
		(property "Author" "Antmicro"
			(at 0 0 0)
			(layer "F.Fab")
			(hide yes)
			(effects
				(font
					(size 1 1)
					(thickness 0.15)
				)
			)
		)
		(property "License" "Apache-2.0"
			(at 0 0 0)
			(layer "F.Fab")
			(hide yes)
			(effects
				(font
					(size 1 1)
					(thickness 0.15)
				)
			)
		)
		(property "MPN" "BSS138PW"
			(at 0 0 0)
			(layer "F.Fab")
			(hide yes)
			(effects
				(font
					(size 1 1)
					(thickness 0.15)
				)
			)
		)
		(property "Manufacturer" "Nexperia"
			(at 0 0 0)
			(layer "F.Fab")
			(hide yes)
			(effects
				(font
					(size 1 1)
					(thickness 0.15)
				)
			)
		)
		(sheetname "User GPIO + LED + button + DIP switch")
		(sheetfile "user-gpio.kicad_sch")
		(attr smd)
		(fp_line
			(start -0.3 -1)
			(end 0.627 -0.999)
			(stroke
				(width 0.15)
				(type solid)
			)
			(layer "F.SilkS")
		)
		(fp_line
			(start -0.3 1)
			(end 0.627 1.001)
			(stroke
				(width 0.15)
				(type solid)
			)
			(layer "F.SilkS")
		)
		(fp_line
			(start 0.627 -0.6)
			(end 0.627 -0.999)
			(stroke
				(width 0.15)
				(type solid)
			)
			(layer "F.SilkS")
		)
		(fp_line
			(start 0.627 0.6)
			(end 0.627 1.001)
			(stroke
				(width 0.15)
				(type solid)
			)
			(layer "F.SilkS")
		)
		(fp_line
			(start -1.4 1)
			(end -1.4 -1)
			(stroke
				(width 0.05)
				(type solid)
			)
			(layer "F.CrtYd")
		)
		(fp_line
			(start -0.9 -1.3)
			(end -0.9 -1)
			(stroke
				(width 0.05)
				(type solid)
			)
			(layer "F.CrtYd")
		)
		(fp_line
			(start -0.9 -1.3)
			(end 0.9 -1.3)
			(stroke
				(width 0.05)
				(type solid)
			)
			(layer "F.CrtYd")
		)
		(fp_line
			(start -0.9 -1)
			(end -1.4 -1)
			(stroke
				(width 0.05)
				(type solid)
			)
			(layer "F.CrtYd")
		)
		(fp_line
			(start -0.9 1)
			(end -1.4 1)
			(stroke
				(width 0.05)
				(type solid)
			)
			(layer "F.CrtYd")
		)
		(fp_line
			(start -0.9 1.3)
			(end -0.9 1)
			(stroke
				(width 0.05)
				(type solid)
			)
			(layer "F.CrtYd")
		)
		(fp_line
			(start 0.9 -1.3)
			(end 0.9 -0.4)
			(stroke
				(width 0.05)
				(type solid)
			)
			(layer "F.CrtYd")
		)
		(fp_line
			(start 0.9 -0.4)
			(end 1.4 -0.4)
			(stroke
				(width 0.05)
				(type solid)
			)
			(layer "F.CrtYd")
		)
		(fp_line
			(start 0.9 0.4)
			(end 0.9 1.3)
			(stroke
				(width 0.05)
				(type solid)
			)
			(layer "F.CrtYd")
		)
		(fp_line
			(start 0.9 1.3)
			(end -0.9 1.3)
			(stroke
				(width 0.05)
				(type solid)
			)
			(layer "F.CrtYd")
		)
		(fp_line
			(start 1.4 -0.4)
			(end 1.4 0.4)
			(stroke
				(width 0.05)
				(type solid)
			)
			(layer "F.CrtYd")
		)
		(fp_line
			(start 1.4 0.4)
			(end 0.9 0.4)
			(stroke
				(width 0.05)
				(type solid)
			)
			(layer "F.CrtYd")
		)
		(fp_rect
			(start -0.623 -0.999)
			(end 0.627 1.001)
			(stroke
				(width 0.15)
				(type solid)
			)
			(fill no)
			(layer "F.Fab")
		)
		(pad "1" smd rect
			(at -1.051 -0.65 90)
			(size 0.6 0.6)
			(layers "F.Cu" "F.Mask" "F.Paste")
			(net 1303 "/USER_IO.LED_GREEN4")
			(pinfunction "G")
			(pintype "passive")
		)
		(pad "2" smd rect
			(at -1.051 0.65 90)
			(size 0.6 0.6)
			(layers "F.Cu" "F.Mask" "F.Paste")
			(net 1 "GND")
			(pinfunction "S")
			(pintype "passive")
		)
		(pad "3" smd rect
			(at 1.05 0 90)
			(size 0.6 0.6)
			(layers "F.Cu" "F.Mask" "F.Paste")
			(net 27 "Net-(D22-C)")
			(pinfunction "D")
			(pintype "passive")
		)
	)
	(footprint "antmicro-footprints:C_0402_1005Metric"
		(layer "F.Cu")
		(at 262.145 139.3 90)
		(descr "Capacitor SMD 0402")
		(tags "capacitor SMD 0402")
		(property "Reference" "C235"
			(at -3.6 0.355 90)
			(layer "F.SilkS")
			(effects
				(font
					(size 0.7 0.7)
					(thickness 0.15)
				)
				(justify left bottom)
			)
		)
		(property "Value" "C_22p_0402"
			(at 0 1.4 90)
			(layer "F.Fab")
			(effects
				(font
					(size 0.7 0.7)
					(thickness 0.15)
				)
				(justify left bottom)
			)
		)
		(property "Description" "SMD Multilayer Ceramic Capacitor, 22 pF, 50 V, 0402 [1005 Metric], ± 5%, C0G / NP0, CC Series"
			(at 0 0 90)
			(layer "F.Fab")
			(hide yes)
			(effects
				(font
					(size 1.27 1.27)
					(thickness 0.15)
				)
			)
		)
		(property "Author" "Antmicro"
			(at 401.445 -122.845 0)
			(layer "F.Fab")
			(hide yes)
			(effects
				(font
					(size 1 1)
					(thickness 0.15)
				)
			)
		)
		(property "Dielectric" ""
			(at 401.445 -122.845 0)
			(layer "F.Fab")
			(hide yes)
			(effects
				(font
					(size 1 1)
					(thickness 0.15)
				)
			)
		)
		(property "License" "Apache-2.0"
			(at 401.445 -122.845 0)
			(layer "F.Fab")
			(hide yes)
			(effects
				(font
					(size 1 1)
					(thickness 0.15)
				)
			)
		)
		(property "MPN" "CC0402JRNPO9BN220"
			(at 401.445 -122.845 0)
			(layer "F.Fab")
			(hide yes)
			(effects
				(font
					(size 1 1)
					(thickness 0.15)
				)
			)
		)
		(property "Manufacturer" "YAGEO"
			(at 401.445 -122.845 0)
			(layer "F.Fab")
			(hide yes)
			(effects
				(font
					(size 1 1)
					(thickness 0.15)
				)
			)
		)
		(property "Val" "22p"
			(at 401.445 -122.845 0)
			(layer "F.Fab")
			(hide yes)
			(effects
				(font
					(size 1 1)
					(thickness 0.15)
				)
			)
		)
		(property "Voltage" ""
			(at 401.445 -122.845 0)
			(layer "F.Fab")
			(hide yes)
			(effects
				(font
					(size 1 1)
					(thickness 0.15)
				)
			)
		)
		(sheetname "USB PHY")
		(sheetfile "usb-phy.kicad_sch")
		(attr smd)
		(fp_rect
			(start -0.925 -0.47)
			(end 0.925 0.47)
			(stroke
				(width 0.05)
				(type default)
			)
			(fill no)
			(layer "F.CrtYd")
		)
		(fp_line
			(start 0.504 -0.25)
			(end 0.504 0.248)
			(stroke
				(width 0.15)
				(type solid)
			)
			(layer "F.Fab")
		)
		(fp_line
			(start -0.494 -0.25)
			(end 0.504 -0.25)
			(stroke
				(width 0.15)
				(type solid)
			)
			(layer "F.Fab")
		)
		(fp_line
			(start 0.504 0.248)
			(end -0.494 0.248)
			(stroke
				(width 0.15)
				(type solid)
			)
			(layer "F.Fab")
		)
		(fp_line
			(start -0.494 0.248)
			(end -0.494 -0.25)
			(stroke
				(width 0.15)
				(type solid)
			)
			(layer "F.Fab")
		)
		(pad "1" smd roundrect
			(at -0.48 0 90)
			(size 0.59 0.64)
			(layers "F.Cu" "F.Mask" "F.Paste")
			(roundrect_rratio 0.25)
			(net 1 "GND")
			(pintype "passive")
		)
		(pad "2" smd roundrect
			(at 0.48 0 90)
			(size 0.59 0.64)
			(layers "F.Cu" "F.Mask" "F.Paste")
			(roundrect_rratio 0.25)
			(net 713 "/USB PHY/FTDI_XO")
			(pintype "passive")
		)
	)
	(footprint "antmicro-footprints:C_0402_1005Metric"
		(layer "F.Cu")
		(at 219.2 140.975)
		(descr "Capacitor SMD 0402")
		(tags "capacitor SMD 0402")
		(property "Reference" "C371"
			(at -3.65 0.425 0)
			(layer "F.SilkS")
			(effects
				(font
					(size 0.7 0.7)
					(thickness 0.15)
				)
				(justify left bottom)
			)
		)
		(property "Value" "C_100n_0402"
			(at 0 1.4 0)
			(layer "F.Fab")
			(effects
				(font
					(size 0.7 0.7)
					(thickness 0.15)
				)
				(justify left bottom)
			)
		)
		(property "Description" "SMD Multilayer Ceramic Capacitor, 0.1 µF, 50 V, 0402 [1005 Metric], ± 10%, X5R, GRM Series"
			(at 0 0 0)
			(layer "F.Fab")
			(hide yes)
			(effects
				(font
					(size 1.27 1.27)
					(thickness 0.15)
				)
			)
		)
		(property "Author" "Antmicro"
			(at 0 0 0)
			(layer "F.Fab")
			(hide yes)
			(effects
				(font
					(size 1 1)
					(thickness 0.15)
				)
			)
		)
		(property "Dielectric" "X5R"
			(at 0 0 0)
			(layer "F.Fab")
			(hide yes)
			(effects
				(font
					(size 1 1)
					(thickness 0.15)
				)
			)
		)
		(property "License" "Apache-2.0"
			(at 0 0 0)
			(layer "F.Fab")
			(hide yes)
			(effects
				(font
					(size 1 1)
					(thickness 0.15)
				)
			)
		)
		(property "MPN" "GRM155R61H104KE14D"
			(at 0 0 0)
			(layer "F.Fab")
			(hide yes)
			(effects
				(font
					(size 1 1)
					(thickness 0.15)
				)
			)
		)
		(property "Manufacturer" "Murata"
			(at 0 0 0)
			(layer "F.Fab")
			(hide yes)
			(effects
				(font
					(size 1 1)
					(thickness 0.15)
				)
			)
		)
		(property "Val" "100n"
			(at 0 0 0)
			(layer "F.Fab")
			(hide yes)
			(effects
				(font
					(size 1 1)
					(thickness 0.15)
				)
			)
		)
		(property "Voltage" "50V"
			(at 0 0 0)
			(layer "F.Fab")
			(hide yes)
			(effects
				(font
					(size 1 1)
					(thickness 0.15)
				)
			)
		)
		(sheetname "Clocks")
		(sheetfile "clocks.kicad_sch")
		(attr smd)
		(fp_rect
			(start -0.925 -0.47)
			(end 0.925 0.47)
			(stroke
				(width 0.05)
				(type default)
			)
			(fill no)
			(layer "F.CrtYd")
		)
		(fp_line
			(start -0.494 -0.25)
			(end 0.504 -0.25)
			(stroke
				(width 0.15)
				(type solid)
			)
			(layer "F.Fab")
		)
		(fp_line
			(start -0.494 0.248)
			(end -0.494 -0.25)
			(stroke
				(width 0.15)
				(type solid)
			)
			(layer "F.Fab")
		)
		(fp_line
			(start 0.504 -0.25)
			(end 0.504 0.248)
			(stroke
				(width 0.15)
				(type solid)
			)
			(layer "F.Fab")
		)
		(fp_line
			(start 0.504 0.248)
			(end -0.494 0.248)
			(stroke
				(width 0.15)
				(type solid)
			)
			(layer "F.Fab")
		)
		(pad "1" smd roundrect
			(at -0.48 0)
			(size 0.59 0.64)
			(layers "F.Cu" "F.Mask" "F.Paste")
			(roundrect_rratio 0.25)
			(net 24 "+3V3")
			(pintype "passive")
		)
		(pad "2" smd roundrect
			(at 0.48 0)
			(size 0.59 0.64)
			(layers "F.Cu" "F.Mask" "F.Paste")
			(roundrect_rratio 0.25)
			(net 1 "GND")
			(pintype "passive")
		)
	)
	(footprint "antmicro-footprints:R_0402_1005Metric"
		(layer "F.Cu")
		(at 189.915 152.885001 180)
		(descr "Resistor SMD 0402")
		(tags "resistor SMD 0402")
		(property "Reference" "R352"
			(at 1.415 -1.264999 180)
			(layer "F.SilkS")
			(effects
				(font
					(size 0.7 0.7)
					(thickness 0.15)
				)
				(justify left bottom)
			)
		)
		(property "Value" "R_10k_0402"
			(at 0 1.4 180)
			(layer "F.Fab")
			(effects
				(font
					(size 0.7 0.7)
					(thickness 0.15)
				)
				(justify left bottom)
			)
		)
		(property "Description" "SMD Chip Resistor, 10 kohm, ± 1%, 62.5 mW, 0402 [1005 Metric], Thick Film, General Purpose"
			(at 0 0 180)
			(layer "F.Fab")
			(hide yes)
			(effects
				(font
					(size 1.27 1.27)
					(thickness 0.15)
				)
			)
		)
		(property "Author" "Antmicro"
			(at 379.83 305.770002 0)
			(layer "F.Fab")
			(hide yes)
			(effects
				(font
					(size 1 1)
					(thickness 0.15)
				)
			)
		)
		(property "License" "Apache-2.0"
			(at 379.83 305.770002 0)
			(layer "F.Fab")
			(hide yes)
			(effects
				(font
					(size 1 1)
					(thickness 0.15)
				)
			)
		)
		(property "MPN" "CR0402-FX-1002GLF"
			(at 379.83 305.770002 0)
			(layer "F.Fab")
			(hide yes)
			(effects
				(font
					(size 1 1)
					(thickness 0.15)
				)
			)
		)
		(property "Manufacturer" "Bourns"
			(at 379.83 305.770002 0)
			(layer "F.Fab")
			(hide yes)
			(effects
				(font
					(size 1 1)
					(thickness 0.15)
				)
			)
		)
		(property "Tolerance" "1%"
			(at 379.83 305.770002 0)
			(layer "F.Fab")
			(hide yes)
			(effects
				(font
					(size 1 1)
					(thickness 0.15)
				)
			)
		)
		(property "Val" "10k"
			(at 379.83 305.770002 0)
			(layer "F.Fab")
			(hide yes)
			(effects
				(font
					(size 1 1)
					(thickness 0.15)
				)
			)
		)
		(sheetname "Clocks")
		(sheetfile "clocks.kicad_sch")
		(attr smd)
		(fp_rect
			(start -0.925 -0.47)
			(end 0.925 0.47)
			(stroke
				(width 0.05)
				(type default)
			)
			(fill no)
			(layer "F.CrtYd")
		)
		(fp_rect
			(start -0.5 -0.25)
			(end 0.5 0.25)
			(stroke
				(width 0.15)
				(type solid)
			)
			(fill no)
			(layer "F.Fab")
		)
		(pad "1" smd roundrect
			(at -0.48 0 180)
			(size 0.59 0.64)
			(layers "F.Cu" "F.Mask" "F.Paste")
			(roundrect_rratio 0.25)
			(net 1 "GND")
			(pintype "passive")
		)
		(pad "2" smd roundrect
			(at 0.48 0 180)
			(size 0.59 0.64)
			(layers "F.Cu" "F.Mask" "F.Paste")
			(roundrect_rratio 0.25)
			(net 640 "/Clocks/LVDS_XO_200M_ENA")
			(pintype "passive")
		)
	)
	(footprint "antmicro-footprints:SC70-3"
		(layer "F.Cu")
		(at 258.4 95.8)
		(property "Reference" "Q14"
			(at -1.6 1.1 90)
			(layer "F.SilkS")
			(effects
				(font
					(size 0.7 0.7)
					(thickness 0.15)
				)
				(justify left bottom)
			)
		)
		(property "Value" "BSS138PW"
			(at 0 2.3 0)
			(layer "F.Fab")
			(effects
				(font
					(size 0.7 0.7)
					(thickness 0.15)
				)
				(justify left bottom)
			)
		)
		(property "Description" "Power MOSFET, N Channel, 60 V, 320 mA, 0.9 ohm, SOT-323, Surface Mount"
			(at 0 0 0)
			(layer "F.Fab")
			(hide yes)
			(effects
				(font
					(size 1.27 1.27)
					(thickness 0.15)
				)
			)
		)
		(property "Author" "Antmicro"
			(at 0 0 0)
			(layer "F.Fab")
			(hide yes)
			(effects
				(font
					(size 1 1)
					(thickness 0.15)
				)
			)
		)
		(property "License" "Apache-2.0"
			(at 0 0 0)
			(layer "F.Fab")
			(hide yes)
			(effects
				(font
					(size 1 1)
					(thickness 0.15)
				)
			)
		)
		(property "MPN" "BSS138PW"
			(at 0 0 0)
			(layer "F.Fab")
			(hide yes)
			(effects
				(font
					(size 1 1)
					(thickness 0.15)
				)
			)
		)
		(property "Manufacturer" "Nexperia"
			(at 0 0 0)
			(layer "F.Fab")
			(hide yes)
			(effects
				(font
					(size 1 1)
					(thickness 0.15)
				)
			)
		)
		(sheetname "User GPIO + LED + button + DIP switch")
		(sheetfile "user-gpio.kicad_sch")
		(attr smd)
		(fp_line
			(start -0.3 -1)
			(end 0.627 -0.999)
			(stroke
				(width 0.15)
				(type solid)
			)
			(layer "F.SilkS")
		)
		(fp_line
			(start -0.3 1)
			(end 0.627 1.001)
			(stroke
				(width 0.15)
				(type solid)
			)
			(layer "F.SilkS")
		)
		(fp_line
			(start 0.627 -0.6)
			(end 0.627 -0.999)
			(stroke
				(width 0.15)
				(type solid)
			)
			(layer "F.SilkS")
		)
		(fp_line
			(start 0.627 0.6)
			(end 0.627 1.001)
			(stroke
				(width 0.15)
				(type solid)
			)
			(layer "F.SilkS")
		)
		(fp_line
			(start -1.4 1)
			(end -1.4 -1)
			(stroke
				(width 0.05)
				(type solid)
			)
			(layer "F.CrtYd")
		)
		(fp_line
			(start -0.9 -1.3)
			(end -0.9 -1)
			(stroke
				(width 0.05)
				(type solid)
			)
			(layer "F.CrtYd")
		)
		(fp_line
			(start -0.9 -1.3)
			(end 0.9 -1.3)
			(stroke
				(width 0.05)
				(type solid)
			)
			(layer "F.CrtYd")
		)
		(fp_line
			(start -0.9 -1)
			(end -1.4 -1)
			(stroke
				(width 0.05)
				(type solid)
			)
			(layer "F.CrtYd")
		)
		(fp_line
			(start -0.9 1)
			(end -1.4 1)
			(stroke
				(width 0.05)
				(type solid)
			)
			(layer "F.CrtYd")
		)
		(fp_line
			(start -0.9 1.3)
			(end -0.9 1)
			(stroke
				(width 0.05)
				(type solid)
			)
			(layer "F.CrtYd")
		)
		(fp_line
			(start 0.9 -1.3)
			(end 0.9 -0.4)
			(stroke
				(width 0.05)
				(type solid)
			)
			(layer "F.CrtYd")
		)
		(fp_line
			(start 0.9 -0.4)
			(end 1.4 -0.4)
			(stroke
				(width 0.05)
				(type solid)
			)
			(layer "F.CrtYd")
		)
		(fp_line
			(start 0.9 0.4)
			(end 0.9 1.3)
			(stroke
				(width 0.05)
				(type solid)
			)
			(layer "F.CrtYd")
		)
		(fp_line
			(start 0.9 1.3)
			(end -0.9 1.3)
			(stroke
				(width 0.05)
				(type solid)
			)
			(layer "F.CrtYd")
		)
		(fp_line
			(start 1.4 -0.4)
			(end 1.4 0.4)
			(stroke
				(width 0.05)
				(type solid)
			)
			(layer "F.CrtYd")
		)
		(fp_line
			(start 1.4 0.4)
			(end 0.9 0.4)
			(stroke
				(width 0.05)
				(type solid)
			)
			(layer "F.CrtYd")
		)
		(fp_rect
			(start -0.623 -0.999)
			(end 0.627 1.001)
			(stroke
				(width 0.15)
				(type solid)
			)
			(fill no)
			(layer "F.Fab")
		)
		(pad "1" smd rect
			(at -1.051 -0.65 90)
			(size 0.6 0.6)
			(layers "F.Cu" "F.Mask" "F.Paste")
			(net 1304 "/USER_IO.LED_GREEN5")
			(pinfunction "G")
			(pintype "passive")
		)
		(pad "2" smd rect
			(at -1.051 0.65 90)
			(size 0.6 0.6)
			(layers "F.Cu" "F.Mask" "F.Paste")
			(net 1 "GND")
			(pinfunction "S")
			(pintype "passive")
		)
		(pad "3" smd rect
			(at 1.05 0 90)
			(size 0.6 0.6)
			(layers "F.Cu" "F.Mask" "F.Paste")
			(net 768 "Net-(D23-C)")
			(pinfunction "D")
			(pintype "passive")
		)
	)
)
